(kicad_pcb
	(version 20260206)
	(generator "pcbnew")
	(generator_version "10.0")
	(general
		(thickness 1.6)
		(legacy_teardrops no)
	)
	(paper "A4")
	(title_block
		(title "Bryce Canyon_F.DPB_16315-1-OCP.brd")
		(comment 1 "Bryce Canyon / footprints 2088-2094 of 2223")
	)
	(layers
		(0 "F.Cu" signal "TOP")
		(4 "In1.Cu" signal "L2GND")
		(6 "In2.Cu" signal "L3")
		(8 "In3.Cu" signal "L4GND")
		(10 "In4.Cu" signal "L5")
		(12 "In5.Cu" signal "L6VCC")
		(14 "In6.Cu" signal "L7VCC")
		(16 "In7.Cu" signal "L8")
		(18 "In8.Cu" signal "L9GND")
		(20 "In9.Cu" signal "L10")
		(22 "In10.Cu" signal "L11GND")
		(2 "B.Cu" signal "BOTTOM")
		(9 "F.Adhes" user "F.Adhesive")
		(11 "B.Adhes" user "B.Adhesive")
		(13 "F.Paste" user "Package Geometry/Pastemask Top")
		(15 "B.Paste" user "Package Geometry/Pastemask Bottom")
		(5 "F.SilkS" user "Ref Des/Silkscreen Top")
		(7 "B.SilkS" user "Ref Des/Silkscreen Bottom")
		(1 "F.Mask" user "Board Geometry/Soldermask Top")
		(3 "B.Mask" user "Board Geometry/Soldermask Bottom")
		(17 "Dwgs.User" user "User.Drawings")
		(19 "Cmts.User" user "User.Comments")
		(21 "Eco1.User" user "User.Eco1")
		(23 "Eco2.User" user "User.Eco2")
		(25 "Edge.Cuts" user "Board Geometry/Outline")
		(27 "Margin" user)
		(31 "F.CrtYd" user "Package Geometry/Place Bound Top")
		(29 "B.CrtYd" user "Package Geometry/Place Bound Bottom")
		(35 "F.Fab" user "Ref Des/Assembly Top")
		(33 "B.Fab" user "Ref Des/Assembly Bottom")
	)
	(footprint ""
		(layer "B.Cu")
		(at 480.871022 -213.114128 90)
		(property "Reference" "TC8"
			(at 0 0 90)
			(layer "B.SilkS")
			(hide yes)
			(effects
				(font
					(size 1.27 1.27)
				)
				(justify mirror)
			)
		)
		(property "Value" "ST220U10VDM-LGP"
			(at 0 -9.6012 90)
			(unlocked yes)
			(layer "B.Fab")
			(hide yes)
			(effects
				(font
					(size 1.016 1.016)
					(thickness 0.1524)
				)
				(justify mirror)
			)
		)
		(property "Device Type" "CT7343H119"
			(at 0 -11.1252 90)
			(unlocked yes)
			(layer "B.Fab")
			(hide yes)
			(effects
				(font
					(size 1.016 1.016)
					(thickness 0.1524)
				)
				(justify mirror)
			)
		)
		(duplicate_pad_numbers_are_jumpers no)
		(fp_line
			(start 2.286 -4.8768)
			(end 2.286 -2.032)
			(stroke
				(width 0.1524)
				(type default)
			)
			(layer "B.SilkS")
		)
		(fp_line
			(start -2.286 -4.8768)
			(end 2.286 -4.8768)
			(stroke
				(width 0.1524)
				(type default)
			)
			(layer "B.SilkS")
		)
		(fp_line
			(start -2.1082 -4.699)
			(end 2.1082 -4.699)
			(stroke
				(width 0.508)
				(type default)
			)
			(layer "B.SilkS")
		)
		(fp_line
			(start -2.286 -2.032)
			(end -2.286 -4.8768)
			(stroke
				(width 0.1524)
				(type default)
			)
			(layer "B.SilkS")
		)
		(fp_line
			(start -2.286 2.032)
			(end -2.286 4.8768)
			(stroke
				(width 0.1524)
				(type default)
			)
			(layer "B.SilkS")
		)
		(fp_line
			(start 2.286 4.8768)
			(end 2.286 2.032)
			(stroke
				(width 0.1524)
				(type default)
			)
			(layer "B.SilkS")
		)
		(fp_line
			(start -2.286 4.8768)
			(end 2.286 4.8768)
			(stroke
				(width 0.1524)
				(type default)
			)
			(layer "B.SilkS")
		)
		(fp_rect
			(start 2.1463 3.6449)
			(end -2.1463 -3.6449)
			(stroke
				(width 0)
				(type default)
			)
			(fill no)
			(layer "B.CrtYd")
		)
		(fp_poly
			(pts
				(xy 2.54 4.953) (xy 2.54 4.2926) (xy 3.81 4.2926) (xy 3.81 -4.2926) (xy 2.54 -4.2926) (xy 2.54 -4.953)
				(xy -2.54 -4.953) (xy -2.54 -4.2926) (xy -3.81 -4.2926) (xy -3.81 -1.6256) (xy -2.1463 -1.6256)
				(xy -2.1463 -3.6449) (xy 2.1463 -3.6449) (xy 2.1463 3.6449) (xy -2.1463 3.6449) (xy -2.1463 -1.6129)
				(xy -3.81 -1.6129) (xy -3.81 4.2926) (xy -2.54 4.2926) (xy -2.54 4.953)
			)
			(stroke
				(width 0)
				(type default)
			)
			(fill no)
			(layer "B.CrtYd")
		)
		(fp_rect
			(start 3.81 4.2926)
			(end 2.54 -4.2926)
			(stroke
				(width 0)
				(type default)
			)
			(fill no)
			(layer "B.Fab")
		)
		(fp_rect
			(start -2.54 4.2926)
			(end -3.81 -4.2926)
			(stroke
				(width 0)
				(type default)
			)
			(fill no)
			(layer "B.Fab")
		)
		(fp_rect
			(start 2.54 4.953)
			(end -2.54 -4.953)
			(stroke
				(width 0)
				(type default)
			)
			(fill no)
			(layer "B.Fab")
		)
		(pad "1" smd rect
			(at 0 -3.1496 270)
			(size 2.413 2.286)
			(layers "B.Cu" "B.Mask" "B.Paste")
			(net "P5V_A_4")
		)
		(pad "2" smd rect
			(at 0 3.1496 270)
			(size 2.413 2.286)
			(layers "B.Cu" "B.Mask" "B.Paste")
			(net "GND")
		)
		(zone
			(layer "B.Cu")
			(hatch none 0.5)
			(connect_pads
				(clearance 0)
			)
			(min_thickness 0.25)
			(keepout
				(tracks allowed)
				(vias not_allowed)
				(pads allowed)
				(copperpour not_allowed)
				(footprints allowed)
			)
			(placement
				(enabled no)
				(sheetname "")
			)
			(fill
				(thermal_gap 0.5)
				(thermal_bridge_width 0.5)
				(island_removal_mode 0)
			)
			(polygon
				(pts
					(xy 479.181922 -211.602828) (xy 476.273622 -211.602828) (xy 476.273622 -214.625428) (xy 479.169222 -214.625428)
					(xy 479.499422 -214.625428) (xy 479.499422 -211.602828)
				)
			)
		)
		(zone
			(layer "B.Cu")
			(hatch none 0.5)
			(connect_pads
				(clearance 0)
			)
			(min_thickness 0.25)
			(keepout
				(tracks allowed)
				(vias not_allowed)
				(pads allowed)
				(copperpour not_allowed)
				(footprints allowed)
			)
			(placement
				(enabled no)
				(sheetname "")
			)
			(fill
				(thermal_gap 0.5)
				(thermal_bridge_width 0.5)
				(island_removal_mode 0)
			)
			(polygon
				(pts
					(xy 485.468422 -214.625428) (xy 485.468422 -211.602828) (xy 482.572822 -211.602828) (xy 482.242622 -211.602828)
					(xy 482.242622 -214.625428) (xy 482.572822 -214.625428)
				)
			)
		)
	)
	(footprint ""
		(layer "B.Cu")
		(at 482.092 -225.679 90)
		(property "Reference" "TP259"
			(at 0 0 90)
			(layer "B.SilkS")
			(hide yes)
			(effects
				(font
					(size 1.27 1.27)
				)
				(justify mirror)
			)
		)
		(property "Value" "TPAD32-GP"
			(at 0.0508 -1.6764 90)
			(unlocked yes)
			(layer "B.Fab")
			(hide yes)
			(effects
				(font
					(size 1.016 1.016)
					(thickness 0.1524)
				)
				(justify mirror)
			)
		)
		(property "Device Type" "TPAD32"
			(at 0.0508 -3.2004 90)
			(unlocked yes)
			(layer "B.Fab")
			(hide yes)
			(effects
				(font
					(size 1.016 1.016)
					(thickness 0.1524)
				)
				(justify mirror)
			)
		)
		(duplicate_pad_numbers_are_jumpers no)
		(fp_poly
			(pts
				(arc
					(start 0 0.4064)
					(mid 0 -0.4064)
					(end 0 0.4064)
				)
			)
			(stroke
				(width 0)
				(type default)
			)
			(fill no)
			(layer "B.CrtYd")
		)
		(fp_poly
			(pts
				(arc
					(start 0 0.7112)
					(mid 0 -0.7112)
					(end 0 0.7112)
				)
			)
			(stroke
				(width 0)
				(type default)
			)
			(fill no)
			(layer "B.Fab")
		)
		(pad "1" smd circle
			(at 0 0 270)
			(size 0.8128 0.8128)
			(layers "B.Cu" "B.Mask" "B.Paste")
			(net "P5V_A_4_PGOOD")
		)
	)
	(footprint ""
		(layer "B.Cu")
		(at 244.094 -385.7498 180)
		(property "Reference" "C587"
			(at 0 0 0)
			(layer "B.SilkS")
			(hide yes)
			(effects
				(font
					(size 1.27 1.27)
				)
				(justify mirror)
			)
		)
		(property "Value" "SCD015U25V2KX-GP"
			(at -1.1811 -2.7051 180)
			(unlocked yes)
			(layer "B.Fab")
			(hide yes)
			(effects
				(font
					(size 1.016 1.016)
					(thickness 0.1524)
				)
				(justify mirror)
			)
		)
		(property "Device Type" "C402H22"
			(at -1.1811 -4.2291 180)
			(unlocked yes)
			(layer "B.Fab")
			(hide yes)
			(effects
				(font
					(size 1.016 1.016)
					(thickness 0.1524)
				)
				(justify mirror)
			)
		)
		(duplicate_pad_numbers_are_jumpers no)
		(fp_rect
			(start 0.4318 0.9525)
			(end -0.4318 -0.9525)
			(stroke
				(width 0)
				(type default)
			)
			(fill no)
			(layer "B.CrtYd")
		)
		(fp_rect
			(start 0.4318 0.9525)
			(end -0.4318 -0.9525)
			(stroke
				(width 0)
				(type default)
			)
			(fill no)
			(layer "B.Fab")
		)
		(pad "1" smd custom
			(at 0 -0.4445)
			(size 0.1524 0.1524)
			(layers "B.Cu" "B.Mask" "B.Paste")
			(net "MB3_CM_SENSE_P")
			(options
				(clearance outline)
				(anchor circle)
			)
			(primitives
				(gr_poly
					(pts
						(arc
							(start 0.3048 0.2032)
							(mid 0.275042 0.275042)
							(end 0.2032 0.3048)
						)
						(arc
							(start -0.2032 0.3048)
							(mid -0.275042 0.275042)
							(end -0.3048 0.2032)
						)
						(arc
							(start -0.3048 -0.2032)
							(mid -0.275042 -0.275042)
							(end -0.2032 -0.3048)
						)
						(arc
							(start 0.2032 -0.3048)
							(mid 0.275042 -0.275042)
							(end 0.3048 -0.2032)
						)
					)
					(width 0)
					(fill yes)
				)
			)
		)
		(pad "2" smd custom
			(at 0 0.4445)
			(size 0.1524 0.1524)
			(layers "B.Cu" "B.Mask" "B.Paste")
			(net "MB3_CM_SENSE_N")
			(options
				(clearance outline)
				(anchor circle)
			)
			(primitives
				(gr_poly
					(pts
						(arc
							(start 0.3048 0.2032)
							(mid 0.275042 0.275042)
							(end 0.2032 0.3048)
						)
						(arc
							(start -0.2032 0.3048)
							(mid -0.275042 0.275042)
							(end -0.3048 0.2032)
						)
						(arc
							(start -0.3048 -0.2032)
							(mid -0.275042 -0.275042)
							(end -0.2032 -0.3048)
						)
						(arc
							(start 0.2032 -0.3048)
							(mid 0.275042 -0.275042)
							(end 0.3048 -0.2032)
						)
					)
					(width 0)
					(fill yes)
				)
			)
		)
	)
	(footprint ""
		(layer "B.Cu")
		(at 56.4642 -141.2494 90)
		(property "Reference" "L4"
			(at 0 0 90)
			(layer "B.SilkS")
			(hide yes)
			(effects
				(font
					(size 1.27 1.27)
				)
				(justify mirror)
			)
		)
		(property "Value" "IND-1UH-191-GP"
			(at 6.7818 -2.1082 90)
			(unlocked yes)
			(layer "B.Fab")
			(hide yes)
			(effects
				(font
					(size 1.016 1.016)
					(thickness 0.1524)
				)
				(justify mirror)
			)
		)
		(property "Device Type" "L109100-2430-UH119"
			(at 6.7818 -3.6322 90)
			(unlocked yes)
			(layer "B.Fab")
			(hide yes)
			(effects
				(font
					(size 1.016 1.016)
					(thickness 0.1524)
				)
				(justify mirror)
			)
		)
		(duplicate_pad_numbers_are_jumpers no)
		(fp_line
			(start 5.2578 -6.4262)
			(end -5.2578 -6.4262)
			(stroke
				(width 0.1524)
				(type default)
			)
			(layer "B.SilkS")
		)
		(fp_line
			(start -5.2578 -6.4262)
			(end -5.2578 6.4262)
			(stroke
				(width 0.1524)
				(type default)
			)
			(layer "B.SilkS")
		)
		(fp_line
			(start 5.2578 6.4262)
			(end 5.2578 -6.4262)
			(stroke
				(width 0.1524)
				(type default)
			)
			(layer "B.SilkS")
		)
		(fp_line
			(start -5.2578 6.4262)
			(end 5.2578 6.4262)
			(stroke
				(width 0.1524)
				(type default)
			)
			(layer "B.SilkS")
		)
		(fp_rect
			(start 5.0038 5.4229)
			(end -5.0038 -5.4229)
			(stroke
				(width 0)
				(type default)
			)
			(fill no)
			(layer "B.CrtYd")
		)
		(fp_poly
			(pts
				(xy 5.5118 6.5024) (xy 5.5118 -6.5024) (xy -5.5118 -6.5024) (xy -5.5118 -0.8509) (xy -5.0038 -0.8509)
				(xy -5.0038 -5.4229) (xy 5.0038 -5.4229) (xy 5.0038 5.4229) (xy -5.0038 5.4229) (xy -5.0038 -0.8382)
				(xy -5.5118 -0.8382) (xy -5.5118 6.5024)
			)
			(stroke
				(width 0)
				(type default)
			)
			(fill no)
			(layer "B.CrtYd")
		)
		(fp_rect
			(start 5.5118 6.5024)
			(end -5.5118 -6.5024)
			(stroke
				(width 0)
				(type default)
			)
			(fill no)
			(layer "B.Fab")
		)
		(pad "1" smd rect
			(at 0 -4.396994 270)
			(size 3.5052 3.556)
			(layers "B.Cu" "B.Mask" "B.Paste")
			(net "P5V_B_LL")
		)
		(pad "2" smd rect
			(at 0 4.396994 270)
			(size 3.5052 3.556)
			(layers "B.Cu" "B.Mask" "B.Paste")
			(net "P5V_A_2")
		)
	)
	(footprint ""
		(layer "B.Cu")
		(at 187.955428 -229.641908 -90)
		(property "Reference" "R1287"
			(at 0 0 90)
			(layer "B.SilkS")
			(hide yes)
			(effects
				(font
					(size 1.27 1.27)
				)
				(justify mirror)
			)
		)
		(property "Value" "0R2J-2-GP"
			(at -0.064008 -3.993896 270)
			(unlocked yes)
			(layer "B.Fab")
			(hide yes)
			(effects
				(font
					(size 1.016 1.016)
					(thickness 0.1524)
				)
				(justify mirror)
			)
		)
		(property "Device Type" "R402H16"
			(at -0.064008 -5.517896 270)
			(unlocked yes)
			(layer "B.Fab")
			(hide yes)
			(effects
				(font
					(size 1.016 1.016)
					(thickness 0.1524)
				)
				(justify mirror)
			)
		)
		(duplicate_pad_numbers_are_jumpers no)
		(fp_line
			(start -0.508 -0.9398)
			(end 0.508 -0.9398)
			(stroke
				(width 0.1524)
				(type default)
			)
			(layer "B.SilkS")
		)
		(fp_line
			(start 0.508 -0.9398)
			(end 0.508 0.9398)
			(stroke
				(width 0.1524)
				(type default)
			)
			(layer "B.SilkS")
		)
		(fp_rect
			(start 0.508 0.9398)
			(end -0.508 -0.9398)
			(stroke
				(width 0)
				(type default)
			)
			(fill no)
			(layer "B.CrtYd")
		)
		(fp_rect
			(start 0.508 0.9398)
			(end -0.508 -0.9398)
			(stroke
				(width 0)
				(type default)
			)
			(fill no)
			(layer "B.Fab")
		)
		(pad "1" smd custom
			(at 0 -0.4445 90)
			(size 0.1397 0.1397)
			(layers "B.Cu" "B.Mask" "B.Paste")
			(net "P3V3_STBY_VBST_RR")
			(options
				(clearance outline)
				(anchor circle)
			)
			(primitives
				(gr_poly
					(pts
						(arc
							(start -0.1778 0.2794)
							(mid -0.249642 0.249642)
							(end -0.2794 0.1778)
						)
						(arc
							(start -0.2794 -0.1778)
							(mid -0.249642 -0.249642)
							(end -0.1778 -0.2794)
						)
						(arc
							(start 0.1778 -0.2794)
							(mid 0.249642 -0.249642)
							(end 0.2794 -0.1778)
						)
						(arc
							(start 0.2794 0.1778)
							(mid 0.249642 0.249642)
							(end 0.1778 0.2794)
						)
					)
					(width 0)
					(fill yes)
				)
			)
		)
		(pad "2" smd custom
			(at 0 0.4445 90)
			(size 0.1397 0.1397)
			(layers "B.Cu" "B.Mask" "B.Paste")
			(net "P3V3_STBY_VBST")
			(options
				(clearance outline)
				(anchor circle)
			)
			(primitives
				(gr_poly
					(pts
						(arc
							(start -0.1778 0.2794)
							(mid -0.249642 0.249642)
							(end -0.2794 0.1778)
						)
						(arc
							(start -0.2794 -0.1778)
							(mid -0.249642 -0.249642)
							(end -0.1778 -0.2794)
						)
						(arc
							(start 0.1778 -0.2794)
							(mid 0.249642 -0.249642)
							(end 0.2794 -0.1778)
						)
						(arc
							(start 0.2794 0.1778)
							(mid 0.249642 0.249642)
							(end 0.1778 0.2794)
						)
					)
					(width 0)
					(fill yes)
				)
			)
		)
	)
	(footprint ""
		(layer "B.Cu")
		(at 39.5224 -245.8974 90)
		(property "Reference" "L2"
			(at 0 0 90)
			(layer "B.SilkS")
			(hide yes)
			(effects
				(font
					(size 1.27 1.27)
				)
				(justify mirror)
			)
		)
		(property "Value" "IND-1UH-191-GP"
			(at 6.7818 -2.1082 90)
			(unlocked yes)
			(layer "B.Fab")
			(hide yes)
			(effects
				(font
					(size 1.016 1.016)
					(thickness 0.1524)
				)
				(justify mirror)
			)
		)
		(property "Device Type" "L109100-2430-UH119"
			(at 6.7818 -3.6322 90)
			(unlocked yes)
			(layer "B.Fab")
			(hide yes)
			(effects
				(font
					(size 1.016 1.016)
					(thickness 0.1524)
				)
				(justify mirror)
			)
		)
		(duplicate_pad_numbers_are_jumpers no)
		(fp_line
			(start 5.2578 -6.4262)
			(end -5.2578 -6.4262)
			(stroke
				(width 0.1524)
				(type default)
			)
			(layer "B.SilkS")
		)
		(fp_line
			(start -5.2578 -6.4262)
			(end -5.2578 6.4262)
			(stroke
				(width 0.1524)
				(type default)
			)
			(layer "B.SilkS")
		)
		(fp_line
			(start 5.2578 6.4262)
			(end 5.2578 -6.4262)
			(stroke
				(width 0.1524)
				(type default)
			)
			(layer "B.SilkS")
		)
		(fp_line
			(start -5.2578 6.4262)
			(end 5.2578 6.4262)
			(stroke
				(width 0.1524)
				(type default)
			)
			(layer "B.SilkS")
		)
		(fp_rect
			(start 5.0038 5.4229)
			(end -5.0038 -5.4229)
			(stroke
				(width 0)
				(type default)
			)
			(fill no)
			(layer "B.CrtYd")
		)
		(fp_poly
			(pts
				(xy 5.5118 6.5024) (xy 5.5118 -6.5024) (xy -5.5118 -6.5024) (xy -5.5118 -0.8509) (xy -5.0038 -0.8509)
				(xy -5.0038 -5.4229) (xy 5.0038 -5.4229) (xy 5.0038 5.4229) (xy -5.0038 5.4229) (xy -5.0038 -0.8382)
				(xy -5.5118 -0.8382) (xy -5.5118 6.5024)
			)
			(stroke
				(width 0)
				(type default)
			)
			(fill no)
			(layer "B.CrtYd")
		)
		(fp_rect
			(start 5.5118 6.5024)
			(end -5.5118 -6.5024)
			(stroke
				(width 0)
				(type default)
			)
			(fill no)
			(layer "B.Fab")
		)
		(pad "1" smd rect
			(at 0 -4.396994 270)
			(size 3.5052 3.556)
			(layers "B.Cu" "B.Mask" "B.Paste")
			(net "P5V_A_LL")
		)
		(pad "2" smd rect
			(at 0 4.396994 270)
			(size 3.5052 3.556)
			(layers "B.Cu" "B.Mask" "B.Paste")
			(net "P5V_A_1")
		)
	)
	(footprint ""
		(layer "B.Cu")
		(at 188.438282 -220.240606 180)
		(property "Reference" "C679"
			(at 0 0 0)
			(layer "B.SilkS")
			(hide yes)
			(effects
				(font
					(size 1.27 1.27)
				)
				(justify mirror)
			)
		)
		(property "Value" "SC1KP50V2KX-1GP"
			(at -1.1811 -2.7051 180)
			(unlocked yes)
			(layer "B.Fab")
			(hide yes)
			(effects
				(font
					(size 1.016 1.016)
					(thickness 0.1524)
				)
				(justify mirror)
			)
		)
		(property "Device Type" "C402H22"
			(at -1.1811 -4.2291 180)
			(unlocked yes)
			(layer "B.Fab")
			(hide yes)
			(effects
				(font
					(size 1.016 1.016)
					(thickness 0.1524)
				)
				(justify mirror)
			)
		)
		(duplicate_pad_numbers_are_jumpers no)
		(fp_rect
			(start 0.4318 0.9525)
			(end -0.4318 -0.9525)
			(stroke
				(width 0)
				(type default)
			)
			(fill no)
			(layer "B.CrtYd")
		)
		(fp_rect
			(start 0.4318 0.9525)
			(end -0.4318 -0.9525)
			(stroke
				(width 0)
				(type default)
			)
			(fill no)
			(layer "B.Fab")
		)
		(pad "1" smd custom
			(at 0 -0.4445)
			(size 0.1524 0.1524)
			(layers "B.Cu" "B.Mask" "B.Paste")
			(net "P3V3_STBY_VFB_R")
			(options
				(clearance outline)
				(anchor circle)
			)
			(primitives
				(gr_poly
					(pts
						(arc
							(start 0.3048 0.2032)
							(mid 0.275042 0.275042)
							(end 0.2032 0.3048)
						)
						(arc
							(start -0.2032 0.3048)
							(mid -0.275042 0.275042)
							(end -0.3048 0.2032)
						)
						(arc
							(start -0.3048 -0.2032)
							(mid -0.275042 -0.275042)
							(end -0.2032 -0.3048)
						)
						(arc
							(start 0.2032 -0.3048)
							(mid 0.275042 -0.275042)
							(end 0.3048 -0.2032)
						)
					)
					(width 0)
					(fill yes)
				)
			)
		)
		(pad "2" smd custom
			(at 0 0.4445)
			(size 0.1524 0.1524)
			(layers "B.Cu" "B.Mask" "B.Paste")
			(net "P3V3_STBY_VFB")
			(options
				(clearance outline)
				(anchor circle)
			)
			(primitives
				(gr_poly
					(pts
						(arc
							(start 0.3048 0.2032)
							(mid 0.275042 0.275042)
							(end 0.2032 0.3048)
						)
						(arc
							(start -0.2032 0.3048)
							(mid -0.275042 0.275042)
							(end -0.3048 0.2032)
						)
						(arc
							(start -0.3048 -0.2032)
							(mid -0.275042 -0.275042)
							(end -0.2032 -0.3048)
						)
						(arc
							(start 0.2032 -0.3048)
							(mid 0.275042 -0.275042)
							(end 0.3048 -0.2032)
						)
					)
					(width 0)
					(fill yes)
				)
			)
		)
	)
)
